# BASEBOARD_FAB2 (Tioga Pass) — schematic netlist excerpt (pin names and nets, part order shuffled) for the footprints in the layout excerpt that follows; sources: Cadence DE-HDL packaged netlist, KiCad conversion of Wiwynn_Tioga_Pass_MB.brd

J9M1  SCONN288_H44441003  SCONN  pkg PIP  page 84
  \12v\(1)  = P12V_NVDIMM_KLM
  VSS(93)  = GND
  DQ(4)  = M_K_DQ<4>
  VSS(92)  = GND
  DQ(0)  = M_K_DQ<0>
  VSS(91)  = GND
  DQS9P  = M_K_DQS_DP<9>
  DQS9N  = M_K_DQS_DN<9>
  VSS(90)  = GND
  DQ(6)  = M_K_DQ<6>
  VSS(89)  = GND
  DQ(2)  = M_K_DQ<2>
  VSS(88)  = GND
  DQ(12)  = M_K_DQ<12>
  VSS(87)  = GND
  DQ(8)  = M_K_DQ<8>
  VSS(86)  = GND
  DQS10P  = M_K_DQS_DP<10>
  DQS10N  = M_K_DQS_DN<10>
  VSS(85)  = GND
  DQ(14)  = M_K_DQ<14>
  VSS(84)  = GND
  DQ(10)  = M_K_DQ<10>
  VSS(83)  = GND
  DQ(20)  = M_K_DQ<20>
  VSS(82)  = GND
  DQ(16)  = M_K_DQ<16>
  VSS(81)  = GND
  DQS11P  = M_K_DQS_DP<11>
  DQS11N  = M_K_DQS_DN<11>
  VSS(80)  = GND
  DQ(22)  = M_K_DQ<22>
  VSS(79)  = GND
  DQ(18)  = M_K_DQ<18>
  VSS(78)  = GND
  DQ(28)  = M_K_DQ<28>
  VSS(77)  = GND
  DQ(24)  = M_K_DQ<24>
  VSS(76)  = GND
  DQS12P  = M_K_DQS_DP<12>
  DQS12N  = M_K_DQS_DN<12>
  VSS(75)  = GND
  DQ(30)  = M_K_DQ<30>
  VSS(74)  = GND
  DQ(26)  = M_K_DQ<26>
  VSS(73)  = GND
  CB(4)  = M_K_ECC<4>
  VSS(72)  = GND
  CB(0)  = M_K_ECC<0>
  VSS(71)  = GND
  DQS17P  = M_K_DQS_DP<17>
  DQS17N  = M_K_DQS_DN<17>
  VSS(70)  = GND
  CB(6)  = M_K_ECC<6>
  VSS(69)  = GND
  CB(2)  = M_K_ECC<2>
  VSS(68)  = GND
  RESET_N  = M_KLM_RST_N
  VDD(25)  = PVDDQ_KLM
  CKE(0)  = M_K_CKE<2>
  VDD(24)  = PVDDQ_KLM
  ACT_N  = M_K_ACT_N
  BG(0)  = M_K_BG<0>
  VDD(23)  = PVDDQ_KLM
  A12  = M_K_MA<12>
  A9  = M_K_MA<9>
  VDD(22)  = PVDDQ_KLM
  A8  = M_K_MA<8>
  A6  = M_K_MA<6>
  VDD(21)  = PVDDQ_KLM
  A3  = M_K_MA<3>
  A1  = M_K_MA<1>
  VDD(20)  = PVDDQ_KLM
  CK0P  = M_K_CLK_DP<2>
  CK0N  = M_K_CLK_DN<2>
  VDD(19)  = PVDDQ_KLM
  VTT(1)  = PVTT_KLM
  EVENT_N  = FM_DIMM_EVENT_COD_N
  A0  = M_K_MA<0>
  VDD(18)  = PVDDQ_KLM
  BA(0)  = M_K_BA<0>
  A16_RAS_N  = M_K_MA<16>
  VDD(17)  = PVDDQ_KLM
  S0_N  = M_K_CS_N<4>
  VDD(16)  = PVDDQ_KLM
  A15_CAS_N  = M_K_MA<15>
  ODT(0)  = M_K_ODT<2>
  VDD(15)  = PVDDQ_KLM
  S1_N  = M_K_CS_N<5>
  VDD(14)  = PVDDQ_KLM
  ODT(1)  = M_K_ODT<3>
  VDD(13)  = PVDDQ_KLM
  S2_N_C(0)  = M_K_CS_N<6>
  VSS(67)  = GND
  DQ(36)  = M_K_DQ<36>
  VSS(66)  = GND
  DQ(32)  = M_K_DQ<32>
  VSS(65)  = GND
  DQS13P  = M_K_DQS_DP<13>
  DQS13N  = M_K_DQS_DN<13>
  VSS(64)  = GND
  DQ(38)  = M_K_DQ<38>
  VSS(63)  = GND
  DQ(34)  = M_K_DQ<34>
  VSS(62)  = GND
  DQ(44)  = M_K_DQ<44>
  VSS(61)  = GND
  DQ(40)  = M_K_DQ<40>
  VSS(60)  = GND
  DQS14P  = M_K_DQS_DP<14>
  DQS14N  = M_K_DQS_DN<14>
  VSS(59)  = GND
  DQ(46)  = M_K_DQ<46>
  VSS(58)  = GND
  DQ(42)  = M_K_DQ<42>
  VSS(57)  = GND
  DQ(52)  = M_K_DQ<52>
  VSS(56)  = GND
  DQ(48)  = M_K_DQ<48>
  VSS(55)  = GND
  DQS15P  = M_K_DQS_DP<15>
  DQS15N  = M_K_DQS_DN<15>
  VSS(54)  = GND
  DQ(54)  = M_K_DQ<54>
  VSS(53)  = GND
  DQ(50)  = M_K_DQ<50>
  VSS(52)  = GND
  DQ(60)  = M_K_DQ<60>
  VSS(51)  = GND
  DQ(56)  = M_K_DQ<56>
  VSS(50)  = GND
  DQS16P  = M_K_DQS_DP<16>
  DQS16N  = M_K_DQS_DN<16>
  VSS(49)  = GND
  DQ(62)  = M_K_DQ<62>
  VSS(48)  = GND
  DQ(58)  = M_K_DQ<58>
  VSS(47)  = GND
  SA(0)  = PVPP_KLM
  SA(1)  = GND
  SCL  = SMB_DDR_KLM_VPP_SCL
  VPP(4)  = PVPP_KLM
  VPP(3)  = PVPP_KLM
  RFU(2)  = TP_CH_K_DIMM0_RFU_2
  \12v\(0)  = P12V_NVDIMM_KLM
  VREFCA  = M_K_VREF
  VSS(46)  = GND
  DQ(5)  = M_K_DQ<5>
  VSS(45)  = GND
  DQ(1)  = M_K_DQ<1>
  VSS(44)  = GND
  DQS0N  = M_K_DQS_DN<0>
  DQS0P  = M_K_DQS_DP<0>
  VSS(43)  = GND
  DQ(7)  = M_K_DQ<7>
  VSS(42)  = GND
  DQ(3)  = M_K_DQ<3>
  VSS(41)  = GND
  DQ(13)  = M_K_DQ<13>
  VSS(40)  = GND
  DQ(9)  = M_K_DQ<9>
  VSS(39)  = GND
  DQS1N  = M_K_DQS_DN<1>
  DQS1P  = M_K_DQS_DP<1>
  VSS(38)  = GND
  DQ(15)  = M_K_DQ<15>
  VSS(37)  = GND
  DQ(11)  = M_K_DQ<11>
  VSS(36)  = GND
  DQ(21)  = M_K_DQ<21>
  VSS(35)  = GND
  DQ(17)  = M_K_DQ<17>
  VSS(34)  = GND
  DQS2N  = M_K_DQS_DN<2>
  DQS2P  = M_K_DQS_DP<2>
  VSS(33)  = GND
  DQ(23)  = M_K_DQ<23>
  VSS(32)  = GND
  DQ(19)  = M_K_DQ<19>
  VSS(31)  = GND
  DQ(29)  = M_K_DQ<29>
  VSS(30)  = GND
  DQ(25)  = M_K_DQ<25>
  VSS(29)  = GND
  DQS3N  = M_K_DQS_DN<3>
  DQS3P  = M_K_DQS_DP<3>
  VSS(28)  = GND
  DQ(31)  = M_K_DQ<31>
  VSS(27)  = GND
  DQ(27)  = M_K_DQ<27>
  VSS(26)  = GND
  CB(5)  = M_K_ECC<5>
  VSS(25)  = GND
  CB(1)  = M_K_ECC<1>
  VSS(24)  = GND
  DQS8N  = M_K_DQS_DN<8>
  DQS8P  = M_K_DQS_DP<8>
  VSS(23)  = GND
  CB(7)  = M_K_ECC<7>
  VSS(22)  = GND
  CB(3)  = M_K_ECC<3>
  VSS(21)  = GND
  CKE(1)  = M_K_CKE<3>
  VDD(12)  = PVDDQ_KLM
  RFU(0)  = TP_CH_K_DIMM0_RFU_0
  VDD(11)  = PVDDQ_KLM
  BG(1)  = M_K_BG<1>
  ALERT_N  = M_K_ALERT_N
  VDD(10)  = PVDDQ_KLM
  A11  = M_K_MA<11>
  A7  = M_K_MA<7>
  VDD(9)  = PVDDQ_KLM
  A5  = M_K_MA<5>
  A4  = M_K_MA<4>
  VDD(8)  = PVDDQ_KLM
  A2  = M_K_MA<2>
  VDD(7)  = PVDDQ_KLM
  CK1P  = M_K_CLK_DP<3>
  CK1N  = M_K_CLK_DN<3>
  VDD(6)  = PVDDQ_KLM
  VTT(0)  = PVTT_KLM
  PAR  = M_K_PAR
  VDD(5)  = PVDDQ_KLM
  BA(1)  = M_K_BA<1>
  A10  = M_K_MA<10>
  VDD(4)  = PVDDQ_KLM
  RFU(1)  = TP_CH_K_DIMM0_RFU_1
  A14_WE_N  = M_K_MA<14>
  VDD(3)  = PVDDQ_KLM
  SAVE_N_NC  = FM_ADR_COMPLETE_KLM_N
  VDD(2)  = PVDDQ_KLM
  A13  = M_K_MA<13>
  VDD(1)  = PVDDQ_KLM
  A17  = M_K_MA<17>
  C(2)  = M_K_C<2>
  VDD(0)  = PVDDQ_KLM
  S3_N_C(1)  = M_K_CS_N<7>
  SA(2)  = GND
  VSS(20)  = GND
  DQ(37)  = M_K_DQ<37>
  VSS(19)  = GND
  DQ(33)  = M_K_DQ<33>
  VSS(18)  = GND
  DQS4N  = M_K_DQS_DN<4>
  DQS4P  = M_K_DQS_DP<4>
  VSS(17)  = GND
  DQ(39)  = M_K_DQ<39>
  VSS(16)  = GND
  DQ(35)  = M_K_DQ<35>
  VSS(15)  = GND
  DQ(45)  = M_K_DQ<45>
  VSS(14)  = GND
  DQ(41)  = M_K_DQ<41>
  VSS(13)  = GND
  DQS5N  = M_K_DQS_DN<5>
  DQS5P  = M_K_DQS_DP<5>
  VSS(12)  = GND
  DQ(47)  = M_K_DQ<47>
  VSS(11)  = GND
  DQ(43)  = M_K_DQ<43>
  VSS(10)  = GND
  DQ(53)  = M_K_DQ<53>
  VSS(9)  = GND
  DQ(49)  = M_K_DQ<49>
  VSS(8)  = GND
  DQS6N  = M_K_DQS_DN<6>
  DQS6P  = M_K_DQS_DP<6>
  VSS(7)  = GND
  DQ(55)  = M_K_DQ<55>
  VSS(6)  = GND
  DQ(51)  = M_K_DQ<51>
  VSS(5)  = GND
  DQ(61)  = M_K_DQ<61>
  VSS(4)  = GND
  DQ(57)  = M_K_DQ<57>
  VSS(3)  = GND
  DQS7N  = M_K_DQS_DN<7>
  DQS7P  = M_K_DQS_DP<7>
  VSS(2)  = GND
  DQ(63)  = M_K_DQ<63>
  VSS(1)  = GND
  DQ(59)  = M_K_DQ<59>
  VSS(0)  = GND
  VDDSPD  = PVPP_KLM
  SDA  = SMB_DDR_KLM_VPP_SDA
  VPP(1)  = PVPP_KLM
  VPP(0)  = PVPP_KLM
  VPP(2)  = PVPP_KLM

(kicad_pcb
	(version 20260206)
	(generator "pcbnew")
	(generator_version "10.0")
	(general
		(thickness 1.6)
		(legacy_teardrops no)
	)
	(paper "A4")
	(title_block
		(title "Wiwynn_Tioga_Pass_MB.brd")
		(comment 1 "Tioga Pass / footprint 2445 of 4770 (J9M1), pads 101-151 of 291")
	)
	(layers
		(0 "F.Cu" signal "TOP")
		(4 "In1.Cu" signal "L2GND")
		(6 "In2.Cu" signal "L3")
		(8 "In3.Cu" signal "L4GND")
		(10 "In4.Cu" signal "L5")
		(12 "In5.Cu" signal "L6GND")
		(14 "In6.Cu" signal "L7VCC")
		(16 "In7.Cu" signal "L8VCC")
		(18 "In8.Cu" signal "L9GND")
		(20 "In9.Cu" signal "L10")
		(22 "In10.Cu" signal "L11GND")
		(24 "In11.Cu" signal "L12")
		(26 "In12.Cu" signal "L13GND")
		(2 "B.Cu" signal "BOTTOM")
		(9 "F.Adhes" user "F.Adhesive")
		(11 "B.Adhes" user "B.Adhesive")
		(13 "F.Paste" user "Package Geometry/Pastemask Top")
		(15 "B.Paste" user "Package Geometry/Pastemask Bottom")
		(5 "F.SilkS" user "Ref Des/Silkscreen Top")
		(7 "B.SilkS" user "Ref Des/Silkscreen Bottom")
		(1 "F.Mask" user "Board Geometry/Soldermask Top")
		(3 "B.Mask" user "Board Geometry/Soldermask Bottom")
		(17 "Dwgs.User" user "User.Drawings")
		(19 "Cmts.User" user "User.Comments")
		(21 "Eco1.User" user "User.Eco1")
		(23 "Eco2.User" user "User.Eco2")
		(25 "Edge.Cuts" user "Board Geometry/Outline")
		(27 "Margin" user)
		(31 "F.CrtYd" user "Package Geometry/Place Bound Top")
		(29 "B.CrtYd" user "Package Geometry/Place Bound Bottom")
		(35 "F.Fab" user "Ref Des/Assembly Top")
		(33 "B.Fab" user "Ref Des/Assembly Bottom")
	)
	(footprint ""
		(layer "B.Cu")
		(at 29.699458 -132.876036 90)
		(property "Reference" "J9M1"
			(at 2.352548 37.991542 0)
			(unlocked yes)
			(layer "B.SilkS")
			(effects
				(font
					(size 0.7874 0.5842)
					(thickness 0.1524)
				)
				(justify left mirror)
			)
		)
		(property "Value" ""
			(at 0 0 90)
			(layer "B.Fab")
			(effects
				(font
					(size 1.27 1.27)
				)
				(justify mirror)
			)
		)
		(duplicate_pad_numbers_are_jumpers no)
		(pad "98" smd rect
			(at 0 87.54999 270)
			(size 1.8034 0.508)
			(layers "B.Cu" "B.Mask" "B.Paste")
			(net "GND")
		)
		(pad "99" smd rect
			(at 0 88.399874 270)
			(size 1.8034 0.508)
			(layers "B.Cu" "B.Mask" "B.Paste")
			(net "M_K_DQS_DP<13>")
		)
		(pad "100" smd rect
			(at 0 89.250012 270)
			(size 1.8034 0.508)
			(layers "B.Cu" "B.Mask" "B.Paste")
			(net "M_K_DQS_DN<13>")
		)
		(pad "101" smd rect
			(at 0 90.099896 270)
			(size 1.8034 0.508)
			(layers "B.Cu" "B.Mask" "B.Paste")
			(net "GND")
		)
		(pad "102" smd rect
			(at 0 90.950034 270)
			(size 1.8034 0.508)
			(layers "B.Cu" "B.Mask" "B.Paste")
			(net "M_K_DQ<38>")
		)
		(pad "103" smd rect
			(at 0 91.799918 270)
			(size 1.8034 0.508)
			(layers "B.Cu" "B.Mask" "B.Paste")
			(net "GND")
		)
		(pad "104" smd rect
			(at 0 92.650056 270)
			(size 1.8034 0.508)
			(layers "B.Cu" "B.Mask" "B.Paste")
			(net "M_K_DQ<34>")
		)
		(pad "105" smd rect
			(at 0 93.49994 270)
			(size 1.8034 0.508)
			(layers "B.Cu" "B.Mask" "B.Paste")
			(net "GND")
		)
		(pad "106" smd rect
			(at 0 94.350078 270)
			(size 1.8034 0.508)
			(layers "B.Cu" "B.Mask" "B.Paste")
			(net "M_K_DQ<44>")
		)
		(pad "107" smd rect
			(at 0 95.199962 270)
			(size 1.8034 0.508)
			(layers "B.Cu" "B.Mask" "B.Paste")
			(net "GND")
		)
		(pad "108" smd rect
			(at 0 96.0501 270)
			(size 1.8034 0.508)
			(layers "B.Cu" "B.Mask" "B.Paste")
			(net "M_K_DQ<40>")
		)
		(pad "109" smd rect
			(at 0 96.899984 270)
			(size 1.8034 0.508)
			(layers "B.Cu" "B.Mask" "B.Paste")
			(net "GND")
		)
		(pad "110" smd rect
			(at 0 97.750122 270)
			(size 1.8034 0.508)
			(layers "B.Cu" "B.Mask" "B.Paste")
			(net "M_K_DQS_DP<14>")
		)
		(pad "111" smd rect
			(at 0 98.600006 270)
			(size 1.8034 0.508)
			(layers "B.Cu" "B.Mask" "B.Paste")
			(net "M_K_DQS_DN<14>")
		)
		(pad "112" smd rect
			(at 0 99.44989 270)
			(size 1.8034 0.508)
			(layers "B.Cu" "B.Mask" "B.Paste")
			(net "GND")
		)
		(pad "113" smd rect
			(at 0 100.300028 270)
			(size 1.8034 0.508)
			(layers "B.Cu" "B.Mask" "B.Paste")
			(net "M_K_DQ<46>")
		)
		(pad "114" smd rect
			(at 0 101.149912 270)
			(size 1.8034 0.508)
			(layers "B.Cu" "B.Mask" "B.Paste")
			(net "GND")
		)
		(pad "115" smd rect
			(at 0 102.00005 270)
			(size 1.8034 0.508)
			(layers "B.Cu" "B.Mask" "B.Paste")
			(net "M_K_DQ<42>")
		)
		(pad "116" smd rect
			(at 0 102.849934 270)
			(size 1.8034 0.508)
			(layers "B.Cu" "B.Mask" "B.Paste")
			(net "GND")
		)
		(pad "117" smd rect
			(at 0 103.700072 270)
			(size 1.8034 0.508)
			(layers "B.Cu" "B.Mask" "B.Paste")
			(net "M_K_DQ<52>")
		)
		(pad "118" smd rect
			(at 0 104.549956 270)
			(size 1.8034 0.508)
			(layers "B.Cu" "B.Mask" "B.Paste")
			(net "GND")
		)
		(pad "119" smd rect
			(at 0 105.400094 270)
			(size 1.8034 0.508)
			(layers "B.Cu" "B.Mask" "B.Paste")
			(net "M_K_DQ<48>")
		)
		(pad "120" smd rect
			(at 0 106.249978 270)
			(size 1.8034 0.508)
			(layers "B.Cu" "B.Mask" "B.Paste")
			(net "GND")
		)
		(pad "121" smd rect
			(at 0 107.100116 270)
			(size 1.8034 0.508)
			(layers "B.Cu" "B.Mask" "B.Paste")
			(net "M_K_DQS_DP<15>")
		)
		(pad "122" smd rect
			(at 0 107.95 270)
			(size 1.8034 0.508)
			(layers "B.Cu" "B.Mask" "B.Paste")
			(net "M_K_DQS_DN<15>")
		)
		(pad "123" smd rect
			(at 0 108.799884 270)
			(size 1.8034 0.508)
			(layers "B.Cu" "B.Mask" "B.Paste")
			(net "GND")
		)
		(pad "124" smd rect
			(at 0 109.650022 270)
			(size 1.8034 0.508)
			(layers "B.Cu" "B.Mask" "B.Paste")
			(net "M_K_DQ<54>")
		)
		(pad "125" smd rect
			(at 0 110.499906 270)
			(size 1.8034 0.508)
			(layers "B.Cu" "B.Mask" "B.Paste")
			(net "GND")
		)
		(pad "126" smd rect
			(at 0 111.350044 270)
			(size 1.8034 0.508)
			(layers "B.Cu" "B.Mask" "B.Paste")
			(net "M_K_DQ<50>")
		)
		(pad "127" smd rect
			(at 0 112.199928 270)
			(size 1.8034 0.508)
			(layers "B.Cu" "B.Mask" "B.Paste")
			(net "GND")
		)
		(pad "128" smd rect
			(at 0 113.050066 270)
			(size 1.8034 0.508)
			(layers "B.Cu" "B.Mask" "B.Paste")
			(net "M_K_DQ<60>")
		)
		(pad "129" smd rect
			(at 0 113.89995 270)
			(size 1.8034 0.508)
			(layers "B.Cu" "B.Mask" "B.Paste")
			(net "GND")
		)
		(pad "130" smd rect
			(at 0 114.750088 270)
			(size 1.8034 0.508)
			(layers "B.Cu" "B.Mask" "B.Paste")
			(net "M_K_DQ<56>")
		)
		(pad "131" smd rect
			(at 0 115.599972 270)
			(size 1.8034 0.508)
			(layers "B.Cu" "B.Mask" "B.Paste")
			(net "GND")
		)
		(pad "132" smd rect
			(at 0 116.45011 270)
			(size 1.8034 0.508)
			(layers "B.Cu" "B.Mask" "B.Paste")
			(net "M_K_DQS_DP<16>")
		)
		(pad "133" smd rect
			(at 0 117.299994 270)
			(size 1.8034 0.508)
			(layers "B.Cu" "B.Mask" "B.Paste")
			(net "M_K_DQS_DN<16>")
		)
		(pad "134" smd rect
			(at 0 118.149878 270)
			(size 1.8034 0.508)
			(layers "B.Cu" "B.Mask" "B.Paste")
			(net "GND")
		)
		(pad "135" smd rect
			(at 0 119.000016 270)
			(size 1.8034 0.508)
			(layers "B.Cu" "B.Mask" "B.Paste")
			(net "M_K_DQ<62>")
		)
		(pad "136" smd rect
			(at 0 119.8499 270)
			(size 1.8034 0.508)
			(layers "B.Cu" "B.Mask" "B.Paste")
			(net "GND")
		)
		(pad "137" smd rect
			(at 0 120.700038 270)
			(size 1.8034 0.508)
			(layers "B.Cu" "B.Mask" "B.Paste")
			(net "M_K_DQ<58>")
		)
		(pad "138" smd rect
			(at 0 121.549922 270)
			(size 1.8034 0.508)
			(layers "B.Cu" "B.Mask" "B.Paste")
			(net "GND")
		)
		(pad "139" smd rect
			(at 0 122.40006 270)
			(size 1.8034 0.508)
			(layers "B.Cu" "B.Mask" "B.Paste")
			(net "PVPP_KLM")
		)
		(pad "140" smd rect
			(at 0 123.249944 270)
			(size 1.8034 0.508)
			(layers "B.Cu" "B.Mask" "B.Paste")
			(net "GND")
		)
		(pad "141" smd rect
			(at 0 124.100082 270)
			(size 1.8034 0.508)
			(layers "B.Cu" "B.Mask" "B.Paste")
			(net "SMB_DDR_KLM_VPP_SCL")
		)
		(pad "142" smd rect
			(at 0 124.949966 270)
			(size 1.8034 0.508)
			(layers "B.Cu" "B.Mask" "B.Paste")
			(net "PVPP_KLM")
		)
		(pad "143" smd rect
			(at 0 125.800104 270)
			(size 1.8034 0.508)
			(layers "B.Cu" "B.Mask" "B.Paste")
			(net "PVPP_KLM")
		)
		(pad "144" smd rect
			(at 0 126.649988 270)
			(size 1.8034 0.508)
			(layers "B.Cu" "B.Mask" "B.Paste")
			(net "TP_CH_K_DIMM0_RFU_2")
		)
		(pad "145" smd rect
			(at -4.59994 0 270)
			(size 1.8034 0.508)
			(layers "B.Cu" "B.Mask" "B.Paste")
			(net "P12V_NVDIMM_KLM")
		)
		(pad "146" smd rect
			(at -4.59994 0.849884 270)
			(size 1.8034 0.508)
			(layers "B.Cu" "B.Mask" "B.Paste")
			(net "M_K_VREF")
		)
		(pad "147" smd rect
			(at -4.59994 1.700022 270)
			(size 1.8034 0.508)
			(layers "B.Cu" "B.Mask" "B.Paste")
			(net "GND")
		)
		(pad "148" smd rect
			(at -4.59994 2.549906 270)
			(size 1.8034 0.508)
			(layers "B.Cu" "B.Mask" "B.Paste")
			(net "M_K_DQ<5>")
		)
	)
)
